# SCM (Grand Teton) — schematic netlist excerpt (pin names and nets, part order shuffled) for the footprints in the layout excerpt that follows; sources: Cadence DE-HDL packaged netlist, KiCad conversion of 12092022_DA0F0TMDCD0_F0T_Management_Board_D_brd_V3_OCP.brd

J10  SCONN11_9192031111LF  SCONN11_91920-31111LF IO  pkg CON_F11S2H2S_P1W4-22_LDH  page 46
  \1\  = SPI_BMC_TPM_CLK_R
  \2\  = RST_BMC_EXTRST_R3_N
  \3\  = SPI_BMC_TPM_MOSI_R
  \4\  = SPI_BMC_TPM_MISO_R
  \5\  = SPI_BMC_TPM_CS2_N_R
  \6\  = SMB_BMC_TPM_MM16_SDA
  \7\  = P3V3_AUX
  \8\  = FM_TPM_PRSNT_1_N
  \9\  = IRQ_BMC_TPM_SPI_R_N
  \10\  = SMB_BMC_TPM_MM16_SCL
  \11\  = GND
  G1  = GND
  G2  = GND

(kicad_pcb
	(version 20260206)
	(generator "pcbnew")
	(generator_version "10.0")
	(general
		(thickness 1.6)
		(legacy_teardrops no)
	)
	(paper "A4")
	(title_block
		(title "12092022_DA0F0TMDCD0_F0T_Management_Board_D_brd_V3_OCP.brd")
		(comment 1 "Grand Teton / footprints 633-633 of 1440")
	)
	(layers
		(0 "F.Cu" signal "TOP")
		(4 "In1.Cu" signal "GND")
		(6 "In2.Cu" signal "IN1")
		(8 "In3.Cu" signal "GND1")
		(10 "In4.Cu" signal "IN2")
		(12 "In5.Cu" signal "VCC")
		(14 "In6.Cu" signal "VCC1")
		(16 "In7.Cu" signal "IN3")
		(18 "In8.Cu" signal "GND2")
		(20 "In9.Cu" signal "IN4")
		(22 "In10.Cu" signal "GND3")
		(2 "B.Cu" signal "BOTTOM")
		(9 "F.Adhes" user "F.Adhesive")
		(11 "B.Adhes" user "B.Adhesive")
		(13 "F.Paste" user "Package Geometry/Pastemask Top")
		(15 "B.Paste" user "Package Geometry/Pastemask Bottom")
		(5 "F.SilkS" user "Ref Des/Silkscreen Top")
		(7 "B.SilkS" user "Ref Des/Silkscreen Bottom")
		(1 "F.Mask" user "Board Geometry/Soldermask Top")
		(3 "B.Mask" user "Board Geometry/Soldermask Bottom")
		(17 "Dwgs.User" user "User.Drawings")
		(19 "Cmts.User" user "User.Comments")
		(21 "Eco1.User" user "User.Eco1")
		(23 "Eco2.User" user "User.Eco2")
		(25 "Edge.Cuts" user "Board Geometry/Outline")
		(27 "Margin" user)
		(31 "F.CrtYd" user "Package Geometry/Place Bound Top")
		(29 "B.CrtYd" user "Package Geometry/Place Bound Bottom")
		(35 "F.Fab" user "Ref Des/Assembly Top")
		(33 "B.Fab" user "Ref Des/Assembly Bottom")
	)
	(footprint ""
		(layer "F.Cu")
		(at 79.202026 -94.856046 180)
		(property "Reference" "J10"
			(at 4.589526 -5.741416 0)
			(unlocked yes)
			(layer "F.SilkS")
			(effects
				(font
					(size 0.7874 0.5842)
					(thickness 0.1524)
				)
				(justify left)
			)
		)
		(property "Value" ""
			(at 0 0 180)
			(layer "F.Fab")
			(effects
				(font
					(size 1.27 1.27)
				)
			)
		)
		(duplicate_pad_numbers_are_jumpers no)
		(fp_line
			(start 2.500122 5.150104)
			(end -2.500122 5.150104)
			(stroke
				(width 0.1524)
				(type default)
			)
			(layer "F.SilkS")
		)
		(fp_line
			(start 2.500122 5.08)
			(end 2.500122 5.150104)
			(stroke
				(width 0.1524)
				(type default)
			)
			(layer "F.SilkS")
		)
		(fp_line
			(start 2.500122 2.4384)
			(end 2.500122 3.3782)
			(stroke
				(width 0.1524)
				(type default)
			)
			(layer "F.SilkS")
		)
		(fp_line
			(start 2.500122 -3.3782)
			(end 2.500122 -2.4384)
			(stroke
				(width 0.1524)
				(type default)
			)
			(layer "F.SilkS")
		)
		(fp_line
			(start 2.500122 -5.150104)
			(end 2.500122 -5.08)
			(stroke
				(width 0.1524)
				(type default)
			)
			(layer "F.SilkS")
		)
		(fp_line
			(start -2.500122 5.150104)
			(end -2.500122 5.08)
			(stroke
				(width 0.1524)
				(type default)
			)
			(layer "F.SilkS")
		)
		(fp_line
			(start -2.500122 3.3782)
			(end -2.500122 2.9464)
			(stroke
				(width 0.1524)
				(type default)
			)
			(layer "F.SilkS")
		)
		(fp_line
			(start -2.500122 -2.9464)
			(end -2.500122 -3.3782)
			(stroke
				(width 0.1524)
				(type default)
			)
			(layer "F.SilkS")
		)
		(fp_line
			(start -2.500122 -5.08)
			(end -2.500122 -5.150104)
			(stroke
				(width 0.1524)
				(type default)
			)
			(layer "F.SilkS")
		)
		(fp_line
			(start -2.500122 -5.150104)
			(end 2.500122 -5.150104)
			(stroke
				(width 0.1524)
				(type default)
			)
			(layer "F.SilkS")
		)
		(fp_poly
			(pts
				(xy -4.0386 -2.068322) (xy -4.0386 -3.084322) (xy -3.0226 -2.576322)
			)
			(stroke
				(width 0)
				(type default)
			)
			(fill yes)
			(layer "F.SilkS")
		)
		(fp_line
			(start 2.500122 5.150104)
			(end 2.500122 -5.150104)
			(stroke
				(width 0.1)
				(type default)
			)
			(layer "F.Fab")
		)
		(fp_line
			(start 2.500122 -5.150104)
			(end -2.500122 -5.150104)
			(stroke
				(width 0.1)
				(type default)
			)
			(layer "F.Fab")
		)
		(fp_line
			(start -2.500122 5.150104)
			(end 2.500122 5.150104)
			(stroke
				(width 0.1)
				(type default)
			)
			(layer "F.Fab")
		)
		(fp_line
			(start -2.500122 -5.150104)
			(end -2.500122 5.150104)
			(stroke
				(width 0.1)
				(type default)
			)
			(layer "F.Fab")
		)
		(fp_poly
			(pts
				(xy -4.0894 -1.992122) (xy -4.0894 -3.008122) (xy -3.0734 -2.500122)
			)
			(stroke
				(width 0)
				(type default)
			)
			(fill yes)
			(layer "F.Fab")
		)
		(fp_text user "11"
			(at 3.814826 2.259584 0)
			(unlocked yes)
			(layer "F.SilkS")
			(effects
				(font
					(size 0.7874 0.5842)
					(thickness 0.1524)
				)
			)
		)
		(fp_text user "7"
			(at 3.535426 -2.566416 0)
			(unlocked yes)
			(layer "F.SilkS")
			(effects
				(font
					(size 0.7874 0.5842)
					(thickness 0.1524)
				)
			)
		)
		(fp_text user "6"
			(at -3.779774 3.341624 180)
			(unlocked yes)
			(layer "F.SilkS")
			(effects
				(font
					(size 0.7874 0.5842)
					(thickness 0.1524)
				)
			)
		)
		(fp_text user "7"
			(at 3.520948 -2.048002 90)
			(unlocked yes)
			(layer "F.Fab")
			(effects
				(font
					(size 0.7874 0.5842)
					(thickness 0.1524)
				)
			)
		)
		(fp_text user "11"
			(at 3.495548 2.028444 90)
			(unlocked yes)
			(layer "F.Fab")
			(effects
				(font
					(size 0.7874 0.5842)
					(thickness 0.1524)
				)
			)
		)
		(fp_text user "6"
			(at -3.591052 2.574798 90)
			(unlocked yes)
			(layer "F.Fab")
			(effects
				(font
					(size 0.7874 0.5842)
					(thickness 0.1524)
				)
			)
		)
		(pad "1" smd rect
			(at -2.109978 -2.500122 270)
			(size 0.6096 1.651)
			(layers "F.Cu" "F.Mask" "F.Paste")
			(net "SPI_BMC_TPM_CLK_R")
		)
		(pad "2" smd rect
			(at -2.109978 -1.500124 270)
			(size 0.6096 1.651)
			(layers "F.Cu" "F.Mask" "F.Paste")
			(net "RST_BMC_EXTRST_R3_N")
		)
		(pad "3" smd rect
			(at -2.109978 -0.499872 270)
			(size 0.6096 1.651)
			(layers "F.Cu" "F.Mask" "F.Paste")
			(net "SPI_BMC_TPM_MOSI_R")
		)
		(pad "4" smd rect
			(at -2.109978 0.499872 270)
			(size 0.6096 1.651)
			(layers "F.Cu" "F.Mask" "F.Paste")
			(net "SPI_BMC_TPM_MISO_R")
		)
		(pad "5" smd rect
			(at -2.109978 1.500124 270)
			(size 0.6096 1.651)
			(layers "F.Cu" "F.Mask" "F.Paste")
			(net "SPI_BMC_TPM_CS2_N_R")
		)
		(pad "6" smd rect
			(at -2.109978 2.500122 270)
			(size 0.6096 1.651)
			(layers "F.Cu" "F.Mask" "F.Paste")
			(net "SMB_BMC_TPM_MM16_SDA")
		)
		(pad "7" smd rect
			(at 2.109978 -1.999996 90)
			(size 0.6096 1.651)
			(layers "F.Cu" "F.Mask" "F.Paste")
			(net "P3V3_AUX")
		)
		(pad "8" smd rect
			(at 2.109978 -0.999998 90)
			(size 0.6096 1.651)
			(layers "F.Cu" "F.Mask" "F.Paste")
			(net "FM_TPM_PRSNT_1_N")
		)
		(pad "9" smd rect
			(at 2.109978 0 90)
			(size 0.6096 1.651)
			(layers "F.Cu" "F.Mask" "F.Paste")
			(net "IRQ_BMC_TPM_SPI_R_N")
		)
		(pad "10" smd rect
			(at 2.109978 0.999998 90)
			(size 0.6096 1.651)
			(layers "F.Cu" "F.Mask" "F.Paste")
			(net "SMB_BMC_TPM_MM16_SCL")
		)
		(pad "11" smd rect
			(at 2.109978 1.999996 90)
			(size 0.6096 1.651)
			(layers "F.Cu" "F.Mask" "F.Paste")
			(net "GND")
		)
		(pad "G1" smd rect
			(at 0 -4.219956 270)
			(size 1.4224 5.8674)
			(layers "F.Cu" "F.Mask" "F.Paste")
			(net "GND")
		)
		(pad "G2" smd rect
			(at 0 4.219956 90)
			(size 1.4224 5.8674)
			(layers "F.Cu" "F.Mask" "F.Paste")
			(net "GND")
		)
	)
)
